(kicad_pcb
	(version 20260206)
	(generator "pcbnew")
	(generator_version "10.0")
	(general
		(thickness 1.6)
		(legacy_teardrops no)
	)
	(paper "A4")
	(title_block
		(title "baseboard — 13948-1b.1110WZS1818.brd")
		(comment 1 "Honey Badger (Wiwynn) / footprints 405-410 of 2523")
	)
	(layers
		(0 "F.Cu" signal "TOP")
		(4 "In1.Cu" signal "L2GND")
		(6 "In2.Cu" signal "L3")
		(8 "In3.Cu" signal "L4VCC")
		(10 "In4.Cu" signal "L5VCC")
		(12 "In5.Cu" signal "L6")
		(14 "In6.Cu" signal "L7GND")
		(2 "B.Cu" signal "BOTTOM")
		(9 "F.Adhes" user "F.Adhesive")
		(11 "B.Adhes" user "B.Adhesive")
		(13 "F.Paste" user "Package Geometry/Pastemask Top")
		(15 "B.Paste" user "Package Geometry/Pastemask Bottom")
		(5 "F.SilkS" user "Ref Des/Silkscreen Top")
		(7 "B.SilkS" user "Ref Des/Silkscreen Bottom")
		(1 "F.Mask" user "Board Geometry/Soldermask Top")
		(3 "B.Mask" user "Board Geometry/Soldermask Bottom")
		(17 "Dwgs.User" user "User.Drawings")
		(19 "Cmts.User" user "User.Comments")
		(21 "Eco1.User" user "User.Eco1")
		(23 "Eco2.User" user "User.Eco2")
		(25 "Edge.Cuts" user "Board Geometry/Outline")
		(27 "Margin" user)
		(31 "F.CrtYd" user "Package Geometry/Place Bound Top")
		(29 "B.CrtYd" user "Package Geometry/Place Bound Bottom")
		(35 "F.Fab" user "Ref Des/Assembly Top")
		(33 "B.Fab" user "Ref Des/Assembly Bottom")
	)
	(footprint ""
		(layer "F.Cu")
		(at 123.703842 -76.906882)
		(property "Reference" "SX2"
			(at 0 0 0)
			(layer "F.SilkS")
			(hide yes)
			(effects
				(font
					(size 1.27 1.27)
				)
			)
		)
		(property "Value" "XTAL-25MHZ-105-GP"
			(at 0.1016 -10.5918 0)
			(unlocked yes)
			(layer "F.Fab")
			(hide yes)
			(effects
				(font
					(size 1.016 1.016)
					(thickness 0.1524)
				)
			)
		)
		(property "Device Type" "SG8002CAPC-4H40"
			(at 0.1016 -12.6238 0)
			(unlocked yes)
			(layer "F.Fab")
			(hide yes)
			(effects
				(font
					(size 1.016 1.016)
					(thickness 0.1524)
				)
			)
		)
		(duplicate_pad_numbers_are_jumpers no)
		(fp_line
			(start -2.8575 -1.9558)
			(end 2.8575 -1.9558)
			(stroke
				(width 0.1524)
				(type default)
			)
			(layer "F.SilkS")
		)
		(fp_line
			(start -2.8575 1.9558)
			(end -2.8575 -1.9558)
			(stroke
				(width 0.1524)
				(type default)
			)
			(layer "F.SilkS")
		)
		(fp_line
			(start 2.8575 -1.9558)
			(end 2.8575 1.9558)
			(stroke
				(width 0.1524)
				(type default)
			)
			(layer "F.SilkS")
		)
		(fp_line
			(start 2.8575 1.9558)
			(end -2.8575 1.9558)
			(stroke
				(width 0.1524)
				(type default)
			)
			(layer "F.SilkS")
		)
		(fp_poly
			(pts
				(xy -2.3114 2.3876) (xy -1.9558 2.032) (xy -1.6002 2.3876)
			)
			(stroke
				(width 0)
				(type default)
			)
			(fill yes)
			(layer "F.SilkS")
		)
		(fp_rect
			(start -2.99974 2.10058)
			(end 2.99974 -2.09931)
			(stroke
				(width 0)
				(type default)
			)
			(fill no)
			(layer "F.CrtYd")
		)
		(fp_rect
			(start -2.3114 2.3876)
			(end -1.6002 2.10058)
			(stroke
				(width 0)
				(type default)
			)
			(fill no)
			(layer "F.CrtYd")
		)
		(fp_poly
			(pts
				(xy -2.3114 2.3876) (xy -2.3114 2.10058) (xy -2.99974 2.10058) (xy -2.99974 -2.09931) (xy 2.99974 -2.09931)
				(xy 2.99974 2.09931) (xy -1.6002 2.09931) (xy -1.6002 2.3876)
			)
			(stroke
				(width 0)
				(type default)
			)
			(fill no)
			(layer "F.Fab")
		)
		(pad "1" smd rect
			(at -1.8034 1.0414)
			(size 1.6002 1.3462)
			(layers "F.Cu" "F.Mask" "F.Paste")
			(net "EXP_REF_CLK_N_R")
		)
		(pad "2" smd rect
			(at 1.8034 1.0414)
			(size 1.6002 1.3462)
			(layers "F.Cu" "F.Mask" "F.Paste")
			(net "GND")
		)
		(pad "3" smd rect
			(at 1.8034 -1.0414)
			(size 1.6002 1.3462)
			(layers "F.Cu" "F.Mask" "F.Paste")
			(net "EXP_REF_CLK_P")
		)
		(pad "4" smd rect
			(at -1.8034 -1.0414)
			(size 1.6002 1.3462)
			(layers "F.Cu" "F.Mask" "F.Paste")
			(net "GND")
		)
		(zone
			(layer "F.Cu")
			(hatch none 0.5)
			(connect_pads
				(clearance 0)
			)
			(min_thickness 0.25)
			(keepout
				(tracks not_allowed)
				(vias allowed)
				(pads allowed)
				(copperpour not_allowed)
				(footprints allowed)
			)
			(placement
				(enabled no)
				(sheetname "")
			)
			(fill
				(thermal_gap 0.5)
				(thermal_bridge_width 0.5)
				(island_removal_mode 0)
			)
			(polygon
				(pts
					(xy 123.195842 -77.287882) (xy 124.211842 -77.287882) (xy 124.211842 -76.525882) (xy 123.195842 -76.525882)
				)
			)
		)
		(zone
			(layer "F.Cu")
			(hatch none 0.5)
			(connect_pads
				(clearance 0)
			)
			(min_thickness 0.25)
			(keepout
				(tracks allowed)
				(vias not_allowed)
				(pads allowed)
				(copperpour not_allowed)
				(footprints allowed)
			)
			(placement
				(enabled no)
				(sheetname "")
			)
			(fill
				(thermal_gap 0.5)
				(thermal_bridge_width 0.5)
				(island_removal_mode 0)
			)
			(polygon
				(pts
					(xy 122.687842 -78.557882) (xy 124.719842 -78.557882) (xy 124.719842 -77.160882) (xy 126.243842 -77.160882)
					(xy 126.243842 -76.652882) (xy 124.719842 -76.652882) (xy 124.719842 -75.255882) (xy 122.687842 -75.255882)
					(xy 122.687842 -76.652882) (xy 121.163842 -76.652882) (xy 121.163842 -77.160882) (xy 122.687842 -77.160882)
				)
			)
		)
	)
	(footprint ""
		(layer "F.Cu")
		(at 36.449 -171.958)
		(property "Reference" "SQ17"
			(at 0 0 0)
			(layer "F.SilkS")
			(hide yes)
			(effects
				(font
					(size 1.27 1.27)
				)
			)
		)
		(property "Value" "2N7002A-7-GP"
			(at 0.127 -8.9662 0)
			(unlocked yes)
			(layer "F.Fab")
			(hide yes)
			(effects
				(font
					(size 1.016 1.016)
					(thickness 0.1524)
				)
			)
		)
		(property "Device Type" "SOT23DGS2D4H48"
			(at 0.127 -10.4902 0)
			(unlocked yes)
			(layer "F.Fab")
			(hide yes)
			(effects
				(font
					(size 1.016 1.016)
					(thickness 0.1524)
				)
			)
		)
		(duplicate_pad_numbers_are_jumpers no)
		(fp_line
			(start -1.651 -1.778)
			(end -1.651 1.778)
			(stroke
				(width 0.1524)
				(type default)
			)
			(layer "F.SilkS")
		)
		(fp_line
			(start -1.651 1.778)
			(end 1.651 1.778)
			(stroke
				(width 0.1524)
				(type default)
			)
			(layer "F.SilkS")
		)
		(fp_line
			(start 1.651 -1.778)
			(end -1.651 -1.778)
			(stroke
				(width 0.1524)
				(type default)
			)
			(layer "F.SilkS")
		)
		(fp_line
			(start 1.651 1.778)
			(end 1.651 -1.778)
			(stroke
				(width 0.1524)
				(type default)
			)
			(layer "F.SilkS")
		)
		(fp_poly
			(pts
				(xy -1.778 1.8796) (xy -1.778 -1.8796) (xy 1.778 -1.8796) (xy 1.778 1.8796)
			)
			(stroke
				(width 0)
				(type default)
			)
			(fill no)
			(layer "F.CrtYd")
		)
		(fp_poly
			(pts
				(xy -1.778 1.8796) (xy -1.778 -1.8796) (xy 1.778 -1.8796) (xy 1.778 1.8796)
			)
			(stroke
				(width 0)
				(type default)
			)
			(fill no)
			(layer "F.Fab")
		)
		(pad "D" smd custom
			(at 0 -0.9525)
			(size 0.1905 0.1905)
			(layers "F.Cu" "F.Mask" "F.Paste")
			(net "P3V3_STBY_R8")
			(options
				(clearance outline)
				(anchor circle)
			)
			(primitives
				(gr_poly
					(pts
						(arc
							(start -0.1778 0.5715)
							(mid -0.321484 0.511984)
							(end -0.381 0.3683)
						)
						(arc
							(start -0.381 -0.3683)
							(mid -0.321484 -0.511984)
							(end -0.1778 -0.5715)
						)
						(arc
							(start 0.1778 -0.5715)
							(mid 0.321484 -0.511984)
							(end 0.381 -0.3683)
						)
						(arc
							(start 0.381 0.3683)
							(mid 0.321484 0.511984)
							(end 0.1778 0.5715)
						)
					)
					(width 0)
					(fill yes)
				)
			)
		)
		(pad "G" smd custom
			(at -0.98425 0.9525)
			(size 0.1905 0.1905)
			(layers "F.Cu" "F.Mask" "F.Paste")
			(net "DP_BMC_EXP_RST_N")
			(options
				(clearance outline)
				(anchor circle)
			)
			(primitives
				(gr_poly
					(pts
						(arc
							(start -0.1778 0.5715)
							(mid -0.321484 0.511984)
							(end -0.381 0.3683)
						)
						(arc
							(start -0.381 -0.3683)
							(mid -0.321484 -0.511984)
							(end -0.1778 -0.5715)
						)
						(arc
							(start 0.1778 -0.5715)
							(mid 0.321484 -0.511984)
							(end 0.381 -0.3683)
						)
						(arc
							(start 0.381 0.3683)
							(mid 0.321484 0.511984)
							(end 0.1778 0.5715)
						)
					)
					(width 0)
					(fill yes)
				)
			)
		)
		(pad "S" smd custom
			(at 0.98425 0.9525)
			(size 0.1905 0.1905)
			(layers "F.Cu" "F.Mask" "F.Paste")
			(net "GND")
			(options
				(clearance outline)
				(anchor circle)
			)
			(primitives
				(gr_poly
					(pts
						(arc
							(start -0.1778 0.5715)
							(mid -0.321484 0.511984)
							(end -0.381 0.3683)
						)
						(arc
							(start -0.381 -0.3683)
							(mid -0.321484 -0.511984)
							(end -0.1778 -0.5715)
						)
						(arc
							(start 0.1778 -0.5715)
							(mid 0.321484 -0.511984)
							(end 0.381 -0.3683)
						)
						(arc
							(start 0.381 0.3683)
							(mid 0.321484 0.511984)
							(end 0.1778 0.5715)
						)
					)
					(width 0)
					(fill yes)
				)
			)
		)
	)
	(footprint ""
		(layer "F.Cu")
		(at 74.462386 -106.598212 90)
		(property "Reference" "PR168"
			(at 0 0 90)
			(layer "F.SilkS")
			(hide yes)
			(effects
				(font
					(size 1.27 1.27)
				)
			)
		)
		(property "Value" "100KR2F-L1-GP"
			(at 0.064008 -3.993896 90)
			(unlocked yes)
			(layer "F.Fab")
			(hide yes)
			(effects
				(font
					(size 1.016 1.016)
					(thickness 0.1524)
				)
			)
		)
		(property "Device Type" "R402H16"
			(at 0.064008 -5.517896 90)
			(unlocked yes)
			(layer "F.Fab")
			(hide yes)
			(effects
				(font
					(size 1.016 1.016)
					(thickness 0.1524)
				)
			)
		)
		(duplicate_pad_numbers_are_jumpers no)
		(fp_line
			(start 0.508 -0.9398)
			(end -0.508 -0.9398)
			(stroke
				(width 0.1524)
				(type default)
			)
			(layer "F.SilkS")
		)
		(fp_line
			(start -0.508 -0.9398)
			(end -0.508 0.9398)
			(stroke
				(width 0.1524)
				(type default)
			)
			(layer "F.SilkS")
		)
		(fp_rect
			(start -0.508 0.9398)
			(end 0.508 -0.9398)
			(stroke
				(width 0)
				(type default)
			)
			(fill no)
			(layer "F.CrtYd")
		)
		(fp_rect
			(start -0.508 0.9398)
			(end 0.508 -0.9398)
			(stroke
				(width 0)
				(type default)
			)
			(fill no)
			(layer "F.Fab")
		)
		(pad "1" smd custom
			(at 0 -0.4445 90)
			(size 0.1397 0.1397)
			(layers "F.Cu" "F.Mask" "F.Paste")
			(net "P12V")
			(options
				(clearance outline)
				(anchor circle)
			)
			(primitives
				(gr_poly
					(pts
						(arc
							(start -0.1778 -0.2794)
							(mid -0.249642 -0.249642)
							(end -0.2794 -0.1778)
						)
						(arc
							(start -0.2794 0.1778)
							(mid -0.249642 0.249642)
							(end -0.1778 0.2794)
						)
						(arc
							(start 0.1778 0.2794)
							(mid 0.249642 0.249642)
							(end 0.2794 0.1778)
						)
						(arc
							(start 0.2794 -0.1778)
							(mid 0.249642 -0.249642)
							(end 0.1778 -0.2794)
						)
					)
					(width 0)
					(fill yes)
				)
			)
		)
		(pad "2" smd custom
			(at 0 0.4445 90)
			(size 0.1397 0.1397)
			(layers "F.Cu" "F.Mask" "F.Paste")
			(net "P1V8_EN_LV")
			(options
				(clearance outline)
				(anchor circle)
			)
			(primitives
				(gr_poly
					(pts
						(arc
							(start -0.1778 -0.2794)
							(mid -0.249642 -0.249642)
							(end -0.2794 -0.1778)
						)
						(arc
							(start -0.2794 0.1778)
							(mid -0.249642 0.249642)
							(end -0.1778 0.2794)
						)
						(arc
							(start 0.1778 0.2794)
							(mid 0.249642 0.249642)
							(end 0.2794 0.1778)
						)
						(arc
							(start 0.2794 -0.1778)
							(mid 0.249642 -0.249642)
							(end 0.1778 -0.2794)
						)
					)
					(width 0)
					(fill yes)
				)
			)
		)
	)
	(footprint ""
		(layer "F.Cu")
		(at 133.36397 -98.806 180)
		(property "Reference" "SC1270"
			(at 0 0 180)
			(layer "F.SilkS")
			(hide yes)
			(effects
				(font
					(size 1.27 1.27)
				)
			)
		)
		(property "Value" "SCD01U10V1KX-GP"
			(at -2.8321 -1.7399 180)
			(unlocked yes)
			(layer "F.Fab")
			(hide yes)
			(effects
				(font
					(size 1.016 1.016)
					(thickness 0.1524)
				)
			)
		)
		(property "Device Type" "C0201H13"
			(at -2.8321 -3.2639 180)
			(unlocked yes)
			(layer "F.Fab")
			(hide yes)
			(effects
				(font
					(size 1.016 1.016)
					(thickness 0.1524)
				)
			)
		)
		(duplicate_pad_numbers_are_jumpers no)
		(fp_rect
			(start -0.2794 0.6477)
			(end 0.2794 -0.6477)
			(stroke
				(width 0)
				(type default)
			)
			(fill no)
			(layer "F.CrtYd")
		)
		(fp_rect
			(start -0.2794 0.6477)
			(end 0.2794 -0.6477)
			(stroke
				(width 0)
				(type default)
			)
			(fill no)
			(layer "F.Fab")
		)
		(pad "1" smd custom
			(at 0 -0.2794 180)
			(size 0.0762 0.0762)
			(layers "F.Cu" "F.Mask" "F.Paste")
			(net "3X24_SAS_TX22_P")
			(options
				(clearance outline)
				(anchor circle)
			)
			(primitives
				(gr_poly
					(pts
						(arc
							(start 0.1524 -0.127)
							(mid 0.137521 -0.162921)
							(end 0.1016 -0.1778)
						)
						(arc
							(start -0.1016 -0.1778)
							(mid -0.137521 -0.162921)
							(end -0.1524 -0.127)
						)
						(arc
							(start -0.1524 0.127)
							(mid -0.137521 0.162921)
							(end -0.1016 0.1778)
						)
						(arc
							(start 0.1016 0.1778)
							(mid 0.137521 0.162921)
							(end 0.1524 0.127)
						)
					)
					(width 0)
					(fill yes)
				)
			)
		)
		(pad "2" smd custom
			(at 0 0.2794 180)
			(size 0.0762 0.0762)
			(layers "F.Cu" "F.Mask" "F.Paste")
			(net "SAS_EXP_GF_TX_DP2")
			(options
				(clearance outline)
				(anchor circle)
			)
			(primitives
				(gr_poly
					(pts
						(arc
							(start 0.1524 -0.127)
							(mid 0.137521 -0.162921)
							(end 0.1016 -0.1778)
						)
						(arc
							(start -0.1016 -0.1778)
							(mid -0.137521 -0.162921)
							(end -0.1524 -0.127)
						)
						(arc
							(start -0.1524 0.127)
							(mid -0.137521 0.162921)
							(end -0.1016 0.1778)
						)
						(arc
							(start 0.1016 0.1778)
							(mid 0.137521 0.162921)
							(end 0.1524 0.127)
						)
					)
					(width 0)
					(fill yes)
				)
			)
		)
	)
	(footprint ""
		(layer "F.Cu")
		(at 49.53 -224.917 180)
		(property "Reference" "R2108"
			(at 0 0 180)
			(layer "F.SilkS")
			(hide yes)
			(effects
				(font
					(size 1.27 1.27)
				)
			)
		)
		(property "Value" "3K74R2F-GP"
			(at 0.064008 -3.993896 180)
			(unlocked yes)
			(layer "F.Fab")
			(hide yes)
			(effects
				(font
					(size 1.016 1.016)
					(thickness 0.1524)
				)
			)
		)
		(property "Device Type" "R402H16"
			(at 0.064008 -5.517896 180)
			(unlocked yes)
			(layer "F.Fab")
			(hide yes)
			(effects
				(font
					(size 1.016 1.016)
					(thickness 0.1524)
				)
			)
		)
		(duplicate_pad_numbers_are_jumpers no)
		(fp_line
			(start 0.508 -0.9398)
			(end -0.508 -0.9398)
			(stroke
				(width 0.1524)
				(type default)
			)
			(layer "F.SilkS")
		)
		(fp_line
			(start -0.508 -0.9398)
			(end -0.508 0.9398)
			(stroke
				(width 0.1524)
				(type default)
			)
			(layer "F.SilkS")
		)
		(fp_rect
			(start -0.508 0.9398)
			(end 0.508 -0.9398)
			(stroke
				(width 0)
				(type default)
			)
			(fill no)
			(layer "F.CrtYd")
		)
		(fp_rect
			(start -0.508 0.9398)
			(end 0.508 -0.9398)
			(stroke
				(width 0)
				(type default)
			)
			(fill no)
			(layer "F.Fab")
		)
		(pad "1" smd custom
			(at 0 -0.4445 180)
			(size 0.1397 0.1397)
			(layers "F.Cu" "F.Mask" "F.Paste")
			(net "MB0_CM_OV_R")
			(options
				(clearance outline)
				(anchor circle)
			)
			(primitives
				(gr_poly
					(pts
						(arc
							(start -0.1778 -0.2794)
							(mid -0.249642 -0.249642)
							(end -0.2794 -0.1778)
						)
						(arc
							(start -0.2794 0.1778)
							(mid -0.249642 0.249642)
							(end -0.1778 0.2794)
						)
						(arc
							(start 0.1778 0.2794)
							(mid 0.249642 0.249642)
							(end 0.2794 0.1778)
						)
						(arc
							(start 0.2794 -0.1778)
							(mid 0.249642 -0.249642)
							(end 0.1778 -0.2794)
						)
					)
					(width 0)
					(fill yes)
				)
			)
		)
		(pad "2" smd custom
			(at 0 0.4445 180)
			(size 0.1397 0.1397)
			(layers "F.Cu" "F.Mask" "F.Paste")
			(net "AGND_CURRENT_MON")
			(options
				(clearance outline)
				(anchor circle)
			)
			(primitives
				(gr_poly
					(pts
						(arc
							(start -0.1778 -0.2794)
							(mid -0.249642 -0.249642)
							(end -0.2794 -0.1778)
						)
						(arc
							(start -0.2794 0.1778)
							(mid -0.249642 0.249642)
							(end -0.1778 0.2794)
						)
						(arc
							(start 0.1778 0.2794)
							(mid 0.249642 0.249642)
							(end 0.2794 0.1778)
						)
						(arc
							(start 0.2794 -0.1778)
							(mid 0.249642 -0.249642)
							(end 0.1778 -0.2794)
						)
					)
					(width 0)
					(fill yes)
				)
			)
		)
	)
	(footprint ""
		(layer "F.Cu")
		(at 172.47997 -67.183 180)
		(property "Reference" "C294"
			(at 0 0 180)
			(layer "F.SilkS")
			(hide yes)
			(effects
				(font
					(size 1.27 1.27)
				)
			)
		)
		(property "Value" "SCD1U25V2KX-2-GP"
			(at 1.1811 -2.7051 180)
			(unlocked yes)
			(layer "F.Fab")
			(hide yes)
			(effects
				(font
					(size 1.016 1.016)
					(thickness 0.1524)
				)
			)
		)
		(property "Device Type" "C402H22"
			(at 1.1811 -4.2291 180)
			(unlocked yes)
			(layer "F.Fab")
			(hide yes)
			(effects
				(font
					(size 1.016 1.016)
					(thickness 0.1524)
				)
			)
		)
		(duplicate_pad_numbers_are_jumpers no)
		(fp_rect
			(start -0.4318 0.9525)
			(end 0.4318 -0.9525)
			(stroke
				(width 0)
				(type default)
			)
			(fill no)
			(layer "F.CrtYd")
		)
		(fp_rect
			(start -0.4318 0.9525)
			(end 0.4318 -0.9525)
			(stroke
				(width 0)
				(type default)
			)
			(fill no)
			(layer "F.Fab")
		)
		(pad "1" smd custom
			(at 0 -0.4445 180)
			(size 0.1524 0.1524)
			(layers "F.Cu" "F.Mask" "F.Paste")
			(net "GND")
			(options
				(clearance outline)
				(anchor circle)
			)
			(primitives
				(gr_poly
					(pts
						(arc
							(start 0.3048 -0.2032)
							(mid 0.275042 -0.275042)
							(end 0.2032 -0.3048)
						)
						(arc
							(start -0.2032 -0.3048)
							(mid -0.275042 -0.275042)
							(end -0.3048 -0.2032)
						)
						(arc
							(start -0.3048 0.2032)
							(mid -0.275042 0.275042)
							(end -0.2032 0.3048)
						)
						(arc
							(start 0.2032 0.3048)
							(mid 0.275042 0.275042)
							(end 0.3048 0.2032)
						)
					)
					(width 0)
					(fill yes)
				)
			)
		)
		(pad "2" smd custom
			(at 0 0.4445 180)
			(size 0.1524 0.1524)
			(layers "F.Cu" "F.Mask" "F.Paste")
			(net "TP_MSB_B47_CPU_GBE_TX_P")
			(options
				(clearance outline)
				(anchor circle)
			)
			(primitives
				(gr_poly
					(pts
						(arc
							(start 0.3048 -0.2032)
							(mid 0.275042 -0.275042)
							(end 0.2032 -0.3048)
						)
						(arc
							(start -0.2032 -0.3048)
							(mid -0.275042 -0.275042)
							(end -0.3048 -0.2032)
						)
						(arc
							(start -0.3048 0.2032)
							(mid -0.275042 0.275042)
							(end -0.2032 0.3048)
						)
						(arc
							(start 0.2032 0.3048)
							(mid 0.275042 0.275042)
							(end 0.3048 0.2032)
						)
					)
					(width 0)
					(fill yes)
				)
			)
		)
	)
)
